# T6G (Grand Teton) — schematic netlist excerpt (pin names and nets, part order shuffled) for the footprints in the layout excerpt that follows; sources: Cadence DE-HDL packaged netlist, KiCad conversion of 04192023_DAF0TMB3IC0_F0TG_MB_C_brd_V02_OCP.brd

R8037  Q_RES  10K 1% CHIP  pkg 0402LF  page 86 : A = P3V3_AUX ; B = PWRGD_CHAF_CPU0
C1101  Q_CAP_DIFFBUS  DIFF BUS_0.22UF 6.3V 20% X6S  pkg C0201  page 67 : \1\ = P3E_CPU1_P4_TX_C_DN<2> ; \2\ = P3E_CPU1_P4_TX_DN<2>
C895  Q_CAP_DIFFBUS  DIFF BUS_0.22UF 6.3V 20% X6S  pkg C0201  page 64 : \1\ = P5E_CPU0_P3_TX_C_DP<3> ; \2\ = P5E_CPU0_P3_TX_DP<3>
C844  Q_CAP_DIFFBUS  DIFF BUS_0.22UF 6.3V 20% X6S  pkg C0201  page 64 : \1\ = P5E_CPU0_P2_TX_C_DN<12> ; \2\ = P5E_CPU0_P2_TX_DN<12>

(kicad_pcb
	(version 20260206)
	(generator "pcbnew")
	(generator_version "10.0")
	(general
		(thickness 1.6)
		(legacy_teardrops no)
	)
	(paper "A4")
	(title_block
		(title "04192023_DAF0TMB3IC0_F0TG_MB_C_brd_V02_OCP.brd")
		(comment 1 "Grand Teton / footprints 3902-3905 of 8354")
	)
	(layers
		(0 "F.Cu" signal "TOP")
		(4 "In1.Cu" signal "GND")
		(6 "In2.Cu" signal "IN1")
		(8 "In3.Cu" signal "GND1")
		(10 "In4.Cu" signal "IN2")
		(12 "In5.Cu" signal "GND2")
		(14 "In6.Cu" signal "IN3")
		(16 "In7.Cu" signal "GND3")
		(18 "In8.Cu" signal "VCC")
		(20 "In9.Cu" signal "VCC1")
		(22 "In10.Cu" signal "GND4")
		(24 "In11.Cu" signal "IN4")
		(26 "In12.Cu" signal "GND5")
		(28 "In13.Cu" signal "IN5")
		(30 "In14.Cu" signal "GND6")
		(32 "In15.Cu" signal "IN6")
		(34 "In16.Cu" signal "GND7")
		(2 "B.Cu" signal "BOTTOM")
		(9 "F.Adhes" user "F.Adhesive")
		(11 "B.Adhes" user "B.Adhesive")
		(13 "F.Paste" user "Package Geometry/Pastemask Top")
		(15 "B.Paste" user "Package Geometry/Pastemask Bottom")
		(5 "F.SilkS" user "Ref Des/Silkscreen Top")
		(7 "B.SilkS" user "Ref Des/Silkscreen Bottom")
		(1 "F.Mask" user "Board Geometry/Soldermask Top")
		(3 "B.Mask" user "Board Geometry/Soldermask Bottom")
		(17 "Dwgs.User" user "User.Drawings")
		(19 "Cmts.User" user "User.Comments")
		(21 "Eco1.User" user "User.Eco1")
		(23 "Eco2.User" user "User.Eco2")
		(25 "Edge.Cuts" user "Board Geometry/Outline")
		(27 "Margin" user)
		(31 "F.CrtYd" user "Package Geometry/Place Bound Top")
		(29 "B.CrtYd" user "Package Geometry/Place Bound Bottom")
		(35 "F.Fab" user "Ref Des/Assembly Top")
		(33 "B.Fab" user "Ref Des/Assembly Bottom")
	)
	(footprint ""
		(layer "F.Cu")
		(at 210.439 -104.013 180)
		(property "Reference" "R8037"
			(at 0 0 180)
			(layer "F.SilkS")
			(hide yes)
			(effects
				(font
					(size 1.27 1.27)
				)
			)
		)
		(property "Value" ""
			(at 0 0 180)
			(layer "F.Fab")
			(effects
				(font
					(size 1.27 1.27)
				)
			)
		)
		(duplicate_pad_numbers_are_jumpers no)
		(fp_line
			(start 0.7874 0.4064)
			(end -0.7874 0.4064)
			(stroke
				(width 0.1524)
				(type default)
			)
			(layer "F.SilkS")
		)
		(fp_line
			(start 0.7874 -0.4064)
			(end 0.7874 0.4064)
			(stroke
				(width 0.1524)
				(type default)
			)
			(layer "F.SilkS")
		)
		(fp_line
			(start -0.7874 0.4064)
			(end -0.7874 -0.4064)
			(stroke
				(width 0.1524)
				(type default)
			)
			(layer "F.SilkS")
		)
		(fp_line
			(start -0.7874 -0.4064)
			(end 0.7874 -0.4064)
			(stroke
				(width 0.1524)
				(type default)
			)
			(layer "F.SilkS")
		)
		(fp_line
			(start 0.67945 0.3048)
			(end 0.120396 0.3048)
			(stroke
				(width 0.1)
				(type default)
			)
			(layer "F.Fab")
		)
		(fp_line
			(start 0.67945 -0.3048)
			(end 0.67945 0.3048)
			(stroke
				(width 0.1)
				(type default)
			)
			(layer "F.Fab")
		)
		(fp_line
			(start 0.12065 -0.2794)
			(end 0.12065 -0.3048)
			(stroke
				(width 0.1)
				(type default)
			)
			(layer "F.Fab")
		)
		(fp_line
			(start 0.12065 -0.3048)
			(end 0.67945 -0.3048)
			(stroke
				(width 0.1)
				(type default)
			)
			(layer "F.Fab")
		)
		(fp_line
			(start 0.120396 0.3048)
			(end 0.120396 0.2794)
			(stroke
				(width 0.1)
				(type default)
			)
			(layer "F.Fab")
		)
		(fp_line
			(start 0.120396 0.2794)
			(end -0.12065 0.2794)
			(stroke
				(width 0.1)
				(type default)
			)
			(layer "F.Fab")
		)
		(fp_line
			(start -0.12065 0.3048)
			(end -0.67945 0.3048)
			(stroke
				(width 0.1)
				(type default)
			)
			(layer "F.Fab")
		)
		(fp_line
			(start -0.12065 0.2794)
			(end -0.12065 0.3048)
			(stroke
				(width 0.1)
				(type default)
			)
			(layer "F.Fab")
		)
		(fp_line
			(start -0.12065 -0.2794)
			(end 0.12065 -0.2794)
			(stroke
				(width 0.1)
				(type default)
			)
			(layer "F.Fab")
		)
		(fp_line
			(start -0.12065 -0.305054)
			(end -0.12065 -0.2794)
			(stroke
				(width 0.1)
				(type default)
			)
			(layer "F.Fab")
		)
		(fp_line
			(start -0.67945 0.3048)
			(end -0.67945 -0.305054)
			(stroke
				(width 0.1)
				(type default)
			)
			(layer "F.Fab")
		)
		(fp_line
			(start -0.67945 -0.305054)
			(end -0.12065 -0.305054)
			(stroke
				(width 0.1)
				(type default)
			)
			(layer "F.Fab")
		)
		(pad "1" smd circle
			(at -0.40005 0 180)
			(size 0 0)
			(layers "F.Cu" "F.Mask" "F.Paste")
			(net "P3V3_AUX")
		)
		(pad "2" smd circle
			(at 0.40005 0 180)
			(size 0 0)
			(layers "F.Cu" "F.Mask" "F.Paste")
			(net "PWRGD_CHAF_CPU0")
		)
	)
	(footprint ""
		(layer "F.Cu")
		(at 421.65524 -378.95403 -90)
		(property "Reference" "C844"
			(at 0 0 270)
			(layer "F.SilkS")
			(hide yes)
			(effects
				(font
					(size 1.27 1.27)
				)
			)
		)
		(property "Value" ""
			(at 0 0 270)
			(layer "F.Fab")
			(effects
				(font
					(size 1.27 1.27)
				)
			)
		)
		(duplicate_pad_numbers_are_jumpers no)
		(fp_line
			(start -0.299974 0.150114)
			(end -0.299974 -0.150114)
			(stroke
				(width 0.1)
				(type default)
			)
			(layer "F.Fab")
		)
		(fp_line
			(start 0.299974 0.150114)
			(end -0.299974 0.150114)
			(stroke
				(width 0.1)
				(type default)
			)
			(layer "F.Fab")
		)
		(fp_line
			(start -0.299974 -0.150114)
			(end 0.299974 -0.150114)
			(stroke
				(width 0.1)
				(type default)
			)
			(layer "F.Fab")
		)
		(fp_line
			(start 0.299974 -0.150114)
			(end 0.299974 0.150114)
			(stroke
				(width 0.1)
				(type default)
			)
			(layer "F.Fab")
		)
		(pad "1" smd rect
			(at -0.2667 0 270)
			(size 0.3048 0.381)
			(layers "F.Cu" "F.Mask" "F.Paste")
			(net "P5E_CPU0_P2_TX_C_DN<12>")
		)
		(pad "2" smd rect
			(at 0.2667 0 270)
			(size 0.3048 0.381)
			(layers "F.Cu" "F.Mask" "F.Paste")
			(net "P5E_CPU0_P2_TX_DN<12>")
		)
	)
	(footprint ""
		(layer "F.Cu")
		(at 367.791492 -378.95403 -90)
		(property "Reference" "C895"
			(at 0 0 270)
			(layer "F.SilkS")
			(hide yes)
			(effects
				(font
					(size 1.27 1.27)
				)
			)
		)
		(property "Value" ""
			(at 0 0 270)
			(layer "F.Fab")
			(effects
				(font
					(size 1.27 1.27)
				)
			)
		)
		(duplicate_pad_numbers_are_jumpers no)
		(fp_line
			(start -0.299974 0.150114)
			(end -0.299974 -0.150114)
			(stroke
				(width 0.1)
				(type default)
			)
			(layer "F.Fab")
		)
		(fp_line
			(start 0.299974 0.150114)
			(end -0.299974 0.150114)
			(stroke
				(width 0.1)
				(type default)
			)
			(layer "F.Fab")
		)
		(fp_line
			(start -0.299974 -0.150114)
			(end 0.299974 -0.150114)
			(stroke
				(width 0.1)
				(type default)
			)
			(layer "F.Fab")
		)
		(fp_line
			(start 0.299974 -0.150114)
			(end 0.299974 0.150114)
			(stroke
				(width 0.1)
				(type default)
			)
			(layer "F.Fab")
		)
		(pad "1" smd rect
			(at -0.2667 0 270)
			(size 0.3048 0.381)
			(layers "F.Cu" "F.Mask" "F.Paste")
			(net "P5E_CPU0_P3_TX_C_DP<3>")
		)
		(pad "2" smd rect
			(at 0.2667 0 270)
			(size 0.3048 0.381)
			(layers "F.Cu" "F.Mask" "F.Paste")
			(net "P5E_CPU0_P3_TX_DP<3>")
		)
	)
	(footprint ""
		(layer "F.Cu")
		(at 180.528468 -50.974498)
		(property "Reference" "C1101"
			(at 0 0 0)
			(layer "F.SilkS")
			(hide yes)
			(effects
				(font
					(size 1.27 1.27)
				)
			)
		)
		(property "Value" ""
			(at 0 0 0)
			(layer "F.Fab")
			(effects
				(font
					(size 1.27 1.27)
				)
			)
		)
		(duplicate_pad_numbers_are_jumpers no)
		(fp_line
			(start -0.299974 -0.150114)
			(end 0.299974 -0.150114)
			(stroke
				(width 0.1)
				(type default)
			)
			(layer "F.Fab")
		)
		(fp_line
			(start -0.299974 0.150114)
			(end -0.299974 -0.150114)
			(stroke
				(width 0.1)
				(type default)
			)
			(layer "F.Fab")
		)
		(fp_line
			(start 0.299974 -0.150114)
			(end 0.299974 0.150114)
			(stroke
				(width 0.1)
				(type default)
			)
			(layer "F.Fab")
		)
		(fp_line
			(start 0.299974 0.150114)
			(end -0.299974 0.150114)
			(stroke
				(width 0.1)
				(type default)
			)
			(layer "F.Fab")
		)
		(pad "1" smd rect
			(at -0.2667 0)
			(size 0.3048 0.381)
			(layers "F.Cu" "F.Mask" "F.Paste")
			(net "P3E_CPU1_P4_TX_C_DN<2>")
		)
		(pad "2" smd rect
			(at 0.2667 0)
			(size 0.3048 0.381)
			(layers "F.Cu" "F.Mask" "F.Paste")
			(net "P3E_CPU1_P4_TX_DN<2>")
		)
	)
)
